# BASEBOARD_FAB2 (Tioga Pass) — schematic netlist excerpt (pin names and nets, part order shuffled) for the footprints in the layout excerpt that follows; sources: Cadence DE-HDL packaged netlist, KiCad conversion of Wiwynn_Tioga_Pass_MB.brd

U8E3  TTL1G126_A  74HC1G126 IC  pkg SOT  page 136
  OE  = RST_PLTRST_TOP_SWAP
  A  = FM_BIOS_TOP_SWAP
  Y  = FM_BIOS_TOP_SWAP_SPKR_R

R4A8  RES  0.0 5% CHIP  pkg 0402  page 156 : A = SMB_LAN_STBY_LVC3_SDA ; B = SMB_PIROM_CPU0_SDA
C6F5  CAP  10UF 4V 20% X6S  pkg 0603LF  page 231 : A = PVPP_ABC ; B = GND

(kicad_pcb
	(version 20260206)
	(generator "pcbnew")
	(generator_version "10.0")
	(general
		(thickness 1.6)
		(legacy_teardrops no)
	)
	(paper "A4")
	(title_block
		(title "Wiwynn_Tioga_Pass_MB.brd")
		(comment 1 "Tioga Pass / footprints 1283-1285 of 4770")
	)
	(layers
		(0 "F.Cu" signal "TOP")
		(4 "In1.Cu" signal "L2GND")
		(6 "In2.Cu" signal "L3")
		(8 "In3.Cu" signal "L4GND")
		(10 "In4.Cu" signal "L5")
		(12 "In5.Cu" signal "L6GND")
		(14 "In6.Cu" signal "L7VCC")
		(16 "In7.Cu" signal "L8VCC")
		(18 "In8.Cu" signal "L9GND")
		(20 "In9.Cu" signal "L10")
		(22 "In10.Cu" signal "L11GND")
		(24 "In11.Cu" signal "L12")
		(26 "In12.Cu" signal "L13GND")
		(2 "B.Cu" signal "BOTTOM")
		(9 "F.Adhes" user "F.Adhesive")
		(11 "B.Adhes" user "B.Adhesive")
		(13 "F.Paste" user "Package Geometry/Pastemask Top")
		(15 "B.Paste" user "Package Geometry/Pastemask Bottom")
		(5 "F.SilkS" user "Ref Des/Silkscreen Top")
		(7 "B.SilkS" user "Ref Des/Silkscreen Bottom")
		(1 "F.Mask" user "Board Geometry/Soldermask Top")
		(3 "B.Mask" user "Board Geometry/Soldermask Bottom")
		(17 "Dwgs.User" user "User.Drawings")
		(19 "Cmts.User" user "User.Comments")
		(21 "Eco1.User" user "User.Eco1")
		(23 "Eco2.User" user "User.Eco2")
		(25 "Edge.Cuts" user "Board Geometry/Outline")
		(27 "Margin" user)
		(31 "F.CrtYd" user "Package Geometry/Place Bound Top")
		(29 "B.CrtYd" user "Package Geometry/Place Bound Bottom")
		(35 "F.Fab" user "Ref Des/Assembly Top")
		(33 "B.Fab" user "Ref Des/Assembly Bottom")
	)
	(footprint ""
		(layer "F.Cu")
		(at 318.543432 -22.740112 -90)
		(property "Reference" "C6F5"
			(at 0 0 270)
			(layer "F.SilkS")
			(hide yes)
			(effects
				(font
					(size 1.27 1.27)
				)
			)
		)
		(property "Value" ""
			(at 0 0 270)
			(layer "F.Fab")
			(effects
				(font
					(size 1.27 1.27)
				)
			)
		)
		(duplicate_pad_numbers_are_jumpers no)
		(fp_poly
			(pts
				(xy -0.4953 -0.2032) (xy 0.4953 -0.2032) (xy 0.4953 1.6002) (xy -0.4953 1.6002)
			)
			(stroke
				(width 0)
				(type default)
			)
			(fill no)
			(layer "F.CrtYd")
		)
		(fp_line
			(start -0.4953 1.6002)
			(end -0.4953 -0.2032)
			(stroke
				(width 0.1)
				(type default)
			)
			(layer "F.Fab")
		)
		(fp_line
			(start 0.4953 1.6002)
			(end -0.4953 1.6002)
			(stroke
				(width 0.1)
				(type default)
			)
			(layer "F.Fab")
		)
		(fp_line
			(start -0.4953 -0.2032)
			(end 0.4953 -0.2032)
			(stroke
				(width 0.1)
				(type default)
			)
			(layer "F.Fab")
		)
		(fp_line
			(start 0.4953 -0.2032)
			(end 0.4953 1.6002)
			(stroke
				(width 0.1)
				(type default)
			)
			(layer "F.Fab")
		)
		(pad "1" smd rect
			(at 0 0 270)
			(size 0.762 0.889)
			(layers "F.Cu" "F.Mask" "F.Paste")
			(net "PVPP_ABC")
		)
		(pad "2" smd rect
			(at 0 1.397 270)
			(size 0.762 0.889)
			(layers "F.Cu" "F.Mask" "F.Paste")
			(net "GND")
		)
		(zone
			(layer "F.Cu")
			(hatch none 0.5)
			(connect_pads
				(clearance 0)
			)
			(min_thickness 0.25)
			(keepout
				(tracks not_allowed)
				(vias allowed)
				(pads allowed)
				(copperpour not_allowed)
				(footprints allowed)
			)
			(placement
				(enabled no)
				(sheetname "")
			)
			(fill
				(thermal_gap 0.5)
				(thermal_bridge_width 0.5)
				(island_removal_mode 0)
			)
			(polygon
				(pts
					(xy 318.098932 -23.121112) (xy 318.098932 -22.359112) (xy 317.590932 -22.359112) (xy 317.590932 -23.121112)
				)
			)
		)
	)
	(footprint ""
		(layer "F.Cu")
		(at 178.981862 -144.998948 90)
		(property "Reference" "R4A8"
			(at 0 0 90)
			(layer "F.SilkS")
			(hide yes)
			(effects
				(font
					(size 1.27 1.27)
				)
			)
		)
		(property "Value" ""
			(at 0 0 90)
			(layer "F.Fab")
			(effects
				(font
					(size 1.27 1.27)
				)
			)
		)
		(duplicate_pad_numbers_are_jumpers no)
		(fp_poly
			(pts
				(xy -0.2794 -0.1016) (xy 0.2794 -0.1016) (xy 0.2794 0.9906) (xy -0.2794 0.9906)
			)
			(stroke
				(width 0)
				(type default)
			)
			(fill no)
			(layer "F.CrtYd")
		)
		(fp_line
			(start 0.2794 -0.1016)
			(end -0.2794 -0.1016)
			(stroke
				(width 0.1)
				(type default)
			)
			(layer "F.Fab")
		)
		(fp_line
			(start -0.2794 -0.1016)
			(end -0.2794 0.9906)
			(stroke
				(width 0.1)
				(type default)
			)
			(layer "F.Fab")
		)
		(fp_line
			(start 0.2794 0.9906)
			(end 0.2794 -0.1016)
			(stroke
				(width 0.1)
				(type default)
			)
			(layer "F.Fab")
		)
		(fp_line
			(start -0.2794 0.9906)
			(end 0.2794 0.9906)
			(stroke
				(width 0.1)
				(type default)
			)
			(layer "F.Fab")
		)
		(pad "1" smd rect
			(at 0 0 90)
			(size 0.508 0.508)
			(layers "F.Cu" "F.Mask" "F.Paste")
			(net "SMB_LAN_STBY_LVC3_SDA")
		)
		(pad "2" smd rect
			(at 0 0.889 90)
			(size 0.508 0.508)
			(layers "F.Cu" "F.Mask" "F.Paste")
			(net "SMB_PIROM_CPU0_SDA")
		)
		(zone
			(layer "F.Cu")
			(hatch none 0.5)
			(connect_pads
				(clearance 0)
			)
			(min_thickness 0.25)
			(keepout
				(tracks allowed)
				(vias not_allowed)
				(pads allowed)
				(copperpour not_allowed)
				(footprints allowed)
			)
			(placement
				(enabled no)
				(sheetname "")
			)
			(fill
				(thermal_gap 0.5)
				(thermal_bridge_width 0.5)
				(island_removal_mode 0)
			)
			(polygon
				(pts
					(xy 179.235862 -144.744948) (xy 179.235862 -145.252948) (xy 179.616862 -145.252948) (xy 179.616862 -144.744948)
				)
			)
		)
		(zone
			(layer "F.Cu")
			(hatch none 0.5)
			(connect_pads
				(clearance 0)
			)
			(min_thickness 0.25)
			(keepout
				(tracks not_allowed)
				(vias allowed)
				(pads allowed)
				(copperpour not_allowed)
				(footprints allowed)
			)
			(placement
				(enabled no)
				(sheetname "")
			)
			(fill
				(thermal_gap 0.5)
				(thermal_bridge_width 0.5)
				(island_removal_mode 0)
			)
			(polygon
				(pts
					(xy 179.616862 -144.744948) (xy 179.616862 -145.252948) (xy 179.235862 -145.252948) (xy 179.235862 -144.744948)
				)
			)
		)
	)
	(footprint ""
		(layer "F.Cu")
		(at 416.56 -56.896 -90)
		(property "Reference" "U8E3"
			(at 0.1778 -2.13487 90)
			(unlocked yes)
			(layer "F.SilkS")
			(effects
				(font
					(size 0.7874 0.5842)
					(thickness 0.1524)
				)
				(justify left)
			)
		)
		(property "Value" ""
			(at 0 0 270)
			(layer "F.Fab")
			(effects
				(font
					(size 1.27 1.27)
				)
			)
		)
		(duplicate_pad_numbers_are_jumpers no)
		(fp_circle
			(center -0.71882 -0.53848)
			(end -0.71882 -0.66548)
			(stroke
				(width 0.254)
				(type default)
			)
			(fill no)
			(layer "F.SilkS")
		)
		(fp_poly
			(pts
				(xy 0.21463 -0.450088) (xy 1.56337 -0.450088) (xy 1.56337 1.75006) (xy 0.21463 1.75006)
			)
			(stroke
				(width 0)
				(type default)
			)
			(fill no)
			(layer "F.CrtYd")
		)
		(fp_line
			(start 0.21463 1.75006)
			(end 0.21463 -0.450088)
			(stroke
				(width 0.1)
				(type default)
			)
			(layer "F.Fab")
		)
		(fp_line
			(start 1.56337 1.75006)
			(end 0.21463 1.75006)
			(stroke
				(width 0.1)
				(type default)
			)
			(layer "F.Fab")
		)
		(fp_line
			(start 0.21463 -0.450088)
			(end 1.56337 -0.450088)
			(stroke
				(width 0.1)
				(type default)
			)
			(layer "F.Fab")
		)
		(fp_line
			(start 1.56337 -0.450088)
			(end 1.56337 1.75006)
			(stroke
				(width 0.1)
				(type default)
			)
			(layer "F.Fab")
		)
		(fp_circle
			(center -0.4699 -0.8382)
			(end -0.4699 -0.9652)
			(stroke
				(width 0.254)
				(type default)
			)
			(fill no)
			(layer "F.Fab")
		)
		(pad "1" smd rect
			(at 0 0 270)
			(size 1.016 0.381)
			(layers "F.Cu" "F.Mask" "F.Paste")
			(net "RST_PLTRST_TOP_SWAP")
		)
		(pad "2" smd rect
			(at 0 0.649986 270)
			(size 1.016 0.381)
			(layers "F.Cu" "F.Mask" "F.Paste")
			(net "FM_BIOS_TOP_SWAP")
		)
		(pad "3" smd rect
			(at 0 1.299972 270)
			(size 1.016 0.381)
			(layers "F.Cu" "F.Mask" "F.Paste")
			(net "GND")
		)
		(pad "4" smd rect
			(at 1.778 1.299972 270)
			(size 1.016 0.381)
			(layers "F.Cu" "F.Mask" "F.Paste")
			(net "FM_BIOS_TOP_SWAP_SPKR_R")
		)
		(pad "5" smd rect
			(at 1.778 0 270)
			(size 1.016 0.381)
			(layers "F.Cu" "F.Mask" "F.Paste")
			(net "P3V3_STBY")
		)
	)
)
